# S9S_MB_2U (Grand Teton) — schematic netlist excerpt (pin names and nets, part order shuffled) for the footprints in the layout excerpt that follows; sources: Cadence DE-HDL packaged netlist, KiCad conversion of 03242023_DA0F0TMBIJ0_F0T_Motherboard_J_brd_V01_OCP.brd

R1813  Q_RES  10K 1% EMPTY  pkg 0402LF  page 239 : A = P3V3_AUX ; B = FM_JTAG_BMC_MUX_SEL
R2789  Q_RES  0 5% EMPTY  pkg 0402LF  page 152 : A = USB2_HOST_BMC_B_BUF_DN ; B = USB2_HUB_BUF_SWB_R_DN

(kicad_pcb
	(version 20260206)
	(generator "pcbnew")
	(generator_version "10.0")
	(general
		(thickness 1.6)
		(legacy_teardrops no)
	)
	(paper "A4")
	(title_block
		(title "03242023_DA0F0TMBIJ0_F0T_Motherboard_J_brd_V01_OCP.brd")
		(comment 1 "Grand Teton / footprints 2910-2911 of 6105")
	)
	(layers
		(0 "F.Cu" signal "TOP")
		(4 "In1.Cu" signal "GND")
		(6 "In2.Cu" signal "IN1")
		(8 "In3.Cu" signal "GND1")
		(10 "In4.Cu" signal "IN2")
		(12 "In5.Cu" signal "GND2")
		(14 "In6.Cu" signal "IN3")
		(16 "In7.Cu" signal "GND3")
		(18 "In8.Cu" signal "VCC")
		(20 "In9.Cu" signal "VCC1")
		(22 "In10.Cu" signal "GND4")
		(24 "In11.Cu" signal "IN4")
		(26 "In12.Cu" signal "GND5")
		(28 "In13.Cu" signal "IN5")
		(30 "In14.Cu" signal "GND6")
		(32 "In15.Cu" signal "IN6")
		(34 "In16.Cu" signal "GND7")
		(2 "B.Cu" signal "BOTTOM")
		(9 "F.Adhes" user "F.Adhesive")
		(11 "B.Adhes" user "B.Adhesive")
		(13 "F.Paste" user "Package Geometry/Pastemask Top")
		(15 "B.Paste" user "Package Geometry/Pastemask Bottom")
		(5 "F.SilkS" user "Ref Des/Silkscreen Top")
		(7 "B.SilkS" user "Ref Des/Silkscreen Bottom")
		(1 "F.Mask" user "Board Geometry/Soldermask Top")
		(3 "B.Mask" user "Board Geometry/Soldermask Bottom")
		(17 "Dwgs.User" user "User.Drawings")
		(19 "Cmts.User" user "User.Comments")
		(21 "Eco1.User" user "User.Eco1")
		(23 "Eco2.User" user "User.Eco2")
		(25 "Edge.Cuts" user "Board Geometry/Outline")
		(27 "Margin" user)
		(31 "F.CrtYd" user "Package Geometry/Place Bound Top")
		(29 "B.CrtYd" user "Package Geometry/Place Bound Bottom")
		(35 "F.Fab" user "Ref Des/Assembly Top")
		(33 "B.Fab" user "Ref Des/Assembly Bottom")
	)
	(footprint ""
		(layer "F.Cu")
		(at 124.672344 -77.571092)
		(property "Reference" "R1813"
			(at 0 0 0)
			(layer "F.SilkS")
			(hide yes)
			(effects
				(font
					(size 1.27 1.27)
				)
			)
		)
		(property "Value" ""
			(at 0 0 0)
			(layer "F.Fab")
			(effects
				(font
					(size 1.27 1.27)
				)
			)
		)
		(duplicate_pad_numbers_are_jumpers no)
		(fp_line
			(start -0.7874 -0.4064)
			(end 0.7874 -0.4064)
			(stroke
				(width 0.1524)
				(type default)
			)
			(layer "F.SilkS")
		)
		(fp_line
			(start -0.7874 0.4064)
			(end -0.7874 -0.4064)
			(stroke
				(width 0.1524)
				(type default)
			)
			(layer "F.SilkS")
		)
		(fp_line
			(start 0.7874 -0.4064)
			(end 0.7874 0.4064)
			(stroke
				(width 0.1524)
				(type default)
			)
			(layer "F.SilkS")
		)
		(fp_line
			(start 0.7874 0.4064)
			(end -0.7874 0.4064)
			(stroke
				(width 0.1524)
				(type default)
			)
			(layer "F.SilkS")
		)
		(fp_line
			(start -0.67945 -0.305054)
			(end -0.12065 -0.305054)
			(stroke
				(width 0.1)
				(type default)
			)
			(layer "F.Fab")
		)
		(fp_line
			(start -0.67945 0.3048)
			(end -0.67945 -0.305054)
			(stroke
				(width 0.1)
				(type default)
			)
			(layer "F.Fab")
		)
		(fp_line
			(start -0.12065 -0.305054)
			(end -0.12065 -0.2794)
			(stroke
				(width 0.1)
				(type default)
			)
			(layer "F.Fab")
		)
		(fp_line
			(start -0.12065 -0.2794)
			(end 0.12065 -0.2794)
			(stroke
				(width 0.1)
				(type default)
			)
			(layer "F.Fab")
		)
		(fp_line
			(start -0.12065 0.2794)
			(end -0.12065 0.3048)
			(stroke
				(width 0.1)
				(type default)
			)
			(layer "F.Fab")
		)
		(fp_line
			(start -0.12065 0.3048)
			(end -0.67945 0.3048)
			(stroke
				(width 0.1)
				(type default)
			)
			(layer "F.Fab")
		)
		(fp_line
			(start 0.120396 0.2794)
			(end -0.12065 0.2794)
			(stroke
				(width 0.1)
				(type default)
			)
			(layer "F.Fab")
		)
		(fp_line
			(start 0.120396 0.3048)
			(end 0.120396 0.2794)
			(stroke
				(width 0.1)
				(type default)
			)
			(layer "F.Fab")
		)
		(fp_line
			(start 0.12065 -0.3048)
			(end 0.67945 -0.3048)
			(stroke
				(width 0.1)
				(type default)
			)
			(layer "F.Fab")
		)
		(fp_line
			(start 0.12065 -0.2794)
			(end 0.12065 -0.3048)
			(stroke
				(width 0.1)
				(type default)
			)
			(layer "F.Fab")
		)
		(fp_line
			(start 0.67945 -0.3048)
			(end 0.67945 0.3048)
			(stroke
				(width 0.1)
				(type default)
			)
			(layer "F.Fab")
		)
		(fp_line
			(start 0.67945 0.3048)
			(end 0.120396 0.3048)
			(stroke
				(width 0.1)
				(type default)
			)
			(layer "F.Fab")
		)
		(pad "1" smd circle
			(at -0.40005 0)
			(size 0 0)
			(layers "F.Cu" "F.Mask" "F.Paste")
			(net "P3V3_AUX")
		)
		(pad "2" smd circle
			(at 0.40005 0)
			(size 0 0)
			(layers "F.Cu" "F.Mask" "F.Paste")
			(net "FM_JTAG_BMC_MUX_SEL")
		)
	)
	(footprint ""
		(layer "F.Cu")
		(at 12.786106 -106.30408 -90)
		(property "Reference" "R2789"
			(at 0 0 270)
			(layer "F.SilkS")
			(hide yes)
			(effects
				(font
					(size 1.27 1.27)
				)
			)
		)
		(property "Value" ""
			(at 0 0 270)
			(layer "F.Fab")
			(effects
				(font
					(size 1.27 1.27)
				)
			)
		)
		(duplicate_pad_numbers_are_jumpers no)
		(fp_line
			(start -0.00254 0.4064)
			(end -0.7874 0.4064)
			(stroke
				(width 0.1524)
				(type default)
			)
			(layer "F.SilkS")
		)
		(fp_line
			(start -0.7874 -0.4064)
			(end 0.7874 -0.4064)
			(stroke
				(width 0.1524)
				(type default)
			)
			(layer "F.SilkS")
		)
		(fp_line
			(start 0.7874 -0.4064)
			(end 0.7874 0.4064)
			(stroke
				(width 0.1524)
				(type default)
			)
			(layer "F.SilkS")
		)
		(fp_line
			(start -0.67945 0.3048)
			(end -0.67945 -0.305054)
			(stroke
				(width 0.1)
				(type default)
			)
			(layer "F.Fab")
		)
		(fp_line
			(start -0.12065 0.3048)
			(end -0.67945 0.3048)
			(stroke
				(width 0.1)
				(type default)
			)
			(layer "F.Fab")
		)
		(fp_line
			(start 0.120396 0.3048)
			(end 0.120396 0.2794)
			(stroke
				(width 0.1)
				(type default)
			)
			(layer "F.Fab")
		)
		(fp_line
			(start 0.67945 0.3048)
			(end 0.120396 0.3048)
			(stroke
				(width 0.1)
				(type default)
			)
			(layer "F.Fab")
		)
		(fp_line
			(start -0.12065 0.2794)
			(end -0.12065 0.3048)
			(stroke
				(width 0.1)
				(type default)
			)
			(layer "F.Fab")
		)
		(fp_line
			(start 0.120396 0.2794)
			(end -0.12065 0.2794)
			(stroke
				(width 0.1)
				(type default)
			)
			(layer "F.Fab")
		)
		(fp_line
			(start -0.12065 -0.2794)
			(end 0.12065 -0.2794)
			(stroke
				(width 0.1)
				(type default)
			)
			(layer "F.Fab")
		)
		(fp_line
			(start 0.12065 -0.2794)
			(end 0.12065 -0.3048)
			(stroke
				(width 0.1)
				(type default)
			)
			(layer "F.Fab")
		)
		(fp_line
			(start 0.12065 -0.3048)
			(end 0.67945 -0.3048)
			(stroke
				(width 0.1)
				(type default)
			)
			(layer "F.Fab")
		)
		(fp_line
			(start 0.67945 -0.3048)
			(end 0.67945 0.3048)
			(stroke
				(width 0.1)
				(type default)
			)
			(layer "F.Fab")
		)
		(fp_line
			(start -0.67945 -0.305054)
			(end -0.12065 -0.305054)
			(stroke
				(width 0.1)
				(type default)
			)
			(layer "F.Fab")
		)
		(fp_line
			(start -0.12065 -0.305054)
			(end -0.12065 -0.2794)
			(stroke
				(width 0.1)
				(type default)
			)
			(layer "F.Fab")
		)
		(pad "1" smd rect
			(at -0.40005 0 90)
			(size 0.4572 0.508)
			(layers "F.Cu" "F.Mask" "F.Paste")
			(net "USB2_HOST_BMC_B_BUF_DN")
		)
		(pad "2" smd rect
			(at 0.40005 0 90)
			(size 0.4572 0.508)
			(layers "F.Cu" "F.Mask" "F.Paste")
			(net "USB2_HUB_BUF_SWB_R_DN")
		)
	)
)
